(kicad_pcb
	(version 20241229)
	(generator "pcbnew")
	(generator_version "9.0")
	(general
		(thickness 1.61)
		(legacy_teardrops no)
	)
	(paper "A3")
	(title_block
		(title "SO-DIMM DDR5 Tester")
		(date "2025-11-26")
		(rev "1.3.0")
		(comment 9 "footprints 84-89 of 627")
	)
	(layers
		(0 "F.Cu" signal)
		(4 "In1.Cu" power)
		(6 "In2.Cu" mixed)
		(8 "In3.Cu" power)
		(10 "In4.Cu" mixed)
		(12 "In5.Cu" power)
		(14 "In6.Cu" mixed)
		(16 "In7.Cu" power)
		(18 "In8.Cu" power)
		(20 "In9.Cu" mixed)
		(22 "In10.Cu" power)
		(2 "B.Cu" signal)
		(9 "F.Adhes" user "F.Adhesive")
		(11 "B.Adhes" user "B.Adhesive")
		(13 "F.Paste" user)
		(15 "B.Paste" user)
		(5 "F.SilkS" user "F.Silkscreen")
		(7 "B.SilkS" user "B.Silkscreen")
		(1 "F.Mask" user)
		(3 "B.Mask" user)
		(17 "Dwgs.User" user "User.Drawings")
		(19 "Cmts.User" user "User.Comments")
		(21 "Eco1.User" user "User.Eco1")
		(23 "Eco2.User" user "User.Eco2")
		(25 "Edge.Cuts" user)
		(27 "Margin" user)
		(31 "F.CrtYd" user "F.Courtyard")
		(29 "B.CrtYd" user "B.Courtyard")
		(35 "F.Fab" user)
		(33 "B.Fab" user)
	)
	(footprint "antmicro-footprints:C_0603_1608Metric"
		(layer "F.Cu")
		(at 199.995501 179.073)
		(descr "Capacitor SMD 0603")
		(tags "capacitor 0603")
		(property "Reference" "C188"
			(at -1.42757 -1.000252 0)
			(layer "F.SilkS")
			(hide yes)
			(effects
				(font
					(size 0.7 0.7)
					(thickness 0.15)
				)
				(justify left bottom)
			)
		)
		(property "Value" "C_22u_0603"
			(at -1.42757 1.770288 0)
			(layer "F.Fab")
			(effects
				(font
					(size 0.7 0.7)
					(thickness 0.15)
				)
				(justify left bottom)
			)
		)
		(property "Datasheet" "https://www.murata.com/products/productdetail?partno=GRM188R60J226MEA0%23"
			(at 0 0 0)
			(layer "F.Fab")
			(hide yes)
			(effects
				(font
					(size 1.27 1.27)
					(thickness 0.15)
				)
			)
		)
		(property "Author" "Antmicro"
			(at 0 0 0)
			(layer "F.Fab")
			(hide yes)
			(effects
				(font
					(size 1 1)
					(thickness 0.15)
				)
			)
		)
		(property "Dielectric" ""
			(at 0 0 0)
			(layer "F.Fab")
			(hide yes)
			(effects
				(font
					(size 1 1)
					(thickness 0.15)
				)
			)
		)
		(property "License" "Apache-2.0"
			(at 0 0 0)
			(layer "F.Fab")
			(hide yes)
			(effects
				(font
					(size 1 1)
					(thickness 0.15)
				)
			)
		)
		(property "MPN" "GRM188R60J226MEA0D"
			(at 0 0 0)
			(layer "F.Fab")
			(hide yes)
			(effects
				(font
					(size 1 1)
					(thickness 0.15)
				)
			)
		)
		(property "Manufacturer" "Murata"
			(at 0 0 0)
			(layer "F.Fab")
			(hide yes)
			(effects
				(font
					(size 1 1)
					(thickness 0.15)
				)
			)
		)
		(property "Val" "22u"
			(at 0 0 0)
			(layer "F.Fab")
			(hide yes)
			(effects
				(font
					(size 1 1)
					(thickness 0.15)
				)
			)
		)
		(property "Voltage" ""
			(at 0 0 0)
			(layer "F.Fab")
			(hide yes)
			(effects
				(font
					(size 1 1)
					(thickness 0.15)
				)
			)
		)
		(sheetname "/Supply/")
		(sheetfile "supply.kicad_sch")
		(attr smd)
		(fp_line
			(start -0.3 -0.3)
			(end 0.3 -0.3)
			(stroke
				(width 0.15)
				(type solid)
			)
			(layer "F.SilkS")
		)
		(fp_line
			(start -0.3 0.3)
			(end 0.3 0.3)
			(stroke
				(width 0.15)
				(type solid)
			)
			(layer "F.SilkS")
		)
		(fp_rect
			(start -1.24 -0.7)
			(end 1.24 0.7)
			(stroke
				(width 0.05)
				(type solid)
			)
			(fill no)
			(layer "F.CrtYd")
		)
		(fp_rect
			(start -0.8 -0.4)
			(end 0.8 0.4)
			(stroke
				(width 0.15)
				(type solid)
			)
			(fill no)
			(layer "F.Fab")
		)
		(pad "1" smd roundrect
			(at -0.7 0)
			(size 0.6 0.8)
			(layers "F.Cu" "F.Mask" "F.Paste")
			(roundrect_rratio 0.2)
			(net 1 "GND")
			(pintype "passive")
		)
		(pad "2" smd roundrect
			(at 0.7 0)
			(size 0.6 0.8)
			(layers "F.Cu" "F.Mask" "F.Paste")
			(roundrect_rratio 0.2)
			(net 35 "/Supply/spare_local")
			(pintype "passive")
		)
	)
	(footprint "antmicro-footprints:TP_SMD_1mm"
		(layer "F.Cu")
		(at 186.4 167.45)
		(property "Reference" "TP11"
			(at 0 -0.731898 0)
			(layer "F.SilkS")
			(hide yes)
			(effects
				(font
					(size 0.7 0.7)
					(thickness 0.15)
				)
				(justify left bottom)
			)
		)
		(property "Value" "TP_1mm_SMD"
			(at 0 1.4 0)
			(layer "F.Fab")
			(effects
				(font
					(size 0.7 0.7)
					(thickness 0.15)
				)
				(justify left bottom)
			)
		)
		(property "Author" "Antmicro"
			(at 0 0 0)
			(layer "F.Fab")
			(hide yes)
			(effects
				(font
					(size 1 1)
					(thickness 0.15)
				)
			)
		)
		(property "License" "Apache-2.0"
			(at 0 0 0)
			(layer "F.Fab")
			(hide yes)
			(effects
				(font
					(size 1 1)
					(thickness 0.15)
				)
			)
		)
		(property "MPN" ""
			(at 0 0 0)
			(layer "F.Fab")
			(hide yes)
			(effects
				(font
					(size 1 1)
					(thickness 0.15)
				)
			)
		)
		(property "Manufacturer" ""
			(at 0 0 0)
			(layer "F.Fab")
			(hide yes)
			(effects
				(font
					(size 1 1)
					(thickness 0.15)
				)
			)
		)
		(sheetname "/Supply/")
		(sheetfile "supply.kicad_sch")
		(attr exclude_from_pos_files)
		(pad "1" smd circle
			(at 0 0)
			(size 1 1)
			(layers "F.Cu" "F.Mask")
			(net 200 "+3V3")
			(pinfunction "1")
			(pintype "passive")
		)
	)
	(footprint "antmicro-footprints:R_0402_1005Metric"
		(layer "F.Cu")
		(at 86.350501 119.926 -90)
		(descr "Resistor SMD 0402")
		(tags "resistor SMD 0402")
		(property "Reference" "R42"
			(at -1.122484 -0.772697 270)
			(layer "F.SilkS")
			(hide yes)
			(effects
				(font
					(size 0.7 0.7)
					(thickness 0.15)
				)
				(justify left bottom)
			)
		)
		(property "Value" "R_330R_0402"
			(at -1.011843 1.772047 270)
			(layer "F.Fab")
			(effects
				(font
					(size 0.7 0.7)
					(thickness 0.15)
				)
				(justify left bottom)
			)
		)
		(property "Datasheet" "https://www.bourns.com/docs/product-datasheets/cr.pdf"
			(at 0 0 270)
			(layer "F.Fab")
			(hide yes)
			(effects
				(font
					(size 1.27 1.27)
					(thickness 0.15)
				)
			)
		)
		(property "Author" "Antmicro"
			(at -33.575499 206.276501 0)
			(layer "F.Fab")
			(hide yes)
			(effects
				(font
					(size 1 1)
					(thickness 0.15)
				)
			)
		)
		(property "License" "Apache-2.0"
			(at -33.575499 206.276501 0)
			(layer "F.Fab")
			(hide yes)
			(effects
				(font
					(size 1 1)
					(thickness 0.15)
				)
			)
		)
		(property "MPN" "CR0402-FX-3300GLF"
			(at -33.575499 206.276501 0)
			(layer "F.Fab")
			(hide yes)
			(effects
				(font
					(size 1 1)
					(thickness 0.15)
				)
			)
		)
		(property "Manufacturer" "Bourns"
			(at -33.575499 206.276501 0)
			(layer "F.Fab")
			(hide yes)
			(effects
				(font
					(size 1 1)
					(thickness 0.15)
				)
			)
		)
		(property "Tolerance" "1%"
			(at -33.575499 206.276501 0)
			(layer "F.Fab")
			(hide yes)
			(effects
				(font
					(size 1 1)
					(thickness 0.15)
				)
			)
		)
		(property "Val" "330R"
			(at -33.575499 206.276501 0)
			(layer "F.Fab")
			(hide yes)
			(effects
				(font
					(size 1 1)
					(thickness 0.15)
				)
			)
		)
		(sheetname "/FPGA bank 14/")
		(sheetfile "fpga-bank-14.kicad_sch")
		(attr smd)
		(fp_rect
			(start -0.93 -0.47)
			(end 0.93 0.47)
			(stroke
				(width 0.05)
				(type solid)
			)
			(fill no)
			(layer "F.CrtYd")
		)
		(fp_rect
			(start -0.5 -0.25)
			(end 0.5 0.25)
			(stroke
				(width 0.15)
				(type solid)
			)
			(fill no)
			(layer "F.Fab")
		)
		(pad "1" smd roundrect
			(at -0.485 0 270)
			(size 0.59 0.64)
			(layers "F.Cu" "F.Mask" "F.Paste")
			(roundrect_rratio 0.25)
			(net 309 "Net-(D6-Pad2)")
			(pintype "passive")
		)
		(pad "2" smd roundrect
			(at 0.485 0 270)
			(size 0.59 0.64)
			(layers "F.Cu" "F.Mask" "F.Paste")
			(roundrect_rratio 0.25)
			(net 355 "Net-(Q6-D)")
			(pintype "passive")
		)
	)
	(footprint "antmicro-footprints:R_1206_3216Metric"
		(layer "F.Cu")
		(at 199 191.325 180)
		(property "Reference" "R144"
			(at 0.8 -2.025 180)
			(layer "F.SilkS")
			(effects
				(font
					(size 0.7 0.7)
					(thickness 0.15)
				)
				(justify left bottom)
			)
		)
		(property "Value" "R_0R01_1206"
			(at -2.422356 2.103591 180)
			(layer "F.Fab")
			(effects
				(font
					(size 0.7 0.7)
					(thickness 0.15)
				)
				(justify left bottom)
			)
		)
		(property "Datasheet" "https://www.yageo.com/upload/media/product/productsearch/datasheet/rchip/PYu-RL_Group_521_RoHS_L_2.pdf"
			(at 0 0 180)
			(layer "F.Fab")
			(hide yes)
			(effects
				(font
					(size 1.27 1.27)
					(thickness 0.15)
				)
			)
		)
		(property "Author" "Antmicro"
			(at 398 382.65 0)
			(layer "F.Fab")
			(hide yes)
			(effects
				(font
					(size 1 1)
					(thickness 0.15)
				)
			)
		)
		(property "License" "Apache-2.0"
			(at 398 382.65 0)
			(layer "F.Fab")
			(hide yes)
			(effects
				(font
					(size 1 1)
					(thickness 0.15)
				)
			)
		)
		(property "MPN" "RL1206FR-7W0R01L"
			(at 398 382.65 0)
			(layer "F.Fab")
			(hide yes)
			(effects
				(font
					(size 1 1)
					(thickness 0.15)
				)
			)
		)
		(property "Manufacturer" "YAGEO"
			(at 398 382.65 0)
			(layer "F.Fab")
			(hide yes)
			(effects
				(font
					(size 1 1)
					(thickness 0.15)
				)
			)
		)
		(property "Tolerance" "1%"
			(at 398 382.65 0)
			(layer "F.Fab")
			(hide yes)
			(effects
				(font
					(size 1 1)
					(thickness 0.15)
				)
			)
		)
		(property "Val" "0R01"
			(at 398 382.65 0)
			(layer "F.Fab")
			(hide yes)
			(effects
				(font
					(size 1 1)
					(thickness 0.15)
				)
			)
		)
		(sheetname "/Supply/")
		(sheetfile "supply.kicad_sch")
		(attr smd)
		(fp_line
			(start 0 0.9)
			(end 0.498 0.9)
			(stroke
				(width 0.15)
				(type solid)
			)
			(layer "F.SilkS")
		)
		(fp_line
			(start 0 0.9)
			(end -0.5 0.9)
			(stroke
				(width 0.15)
				(type solid)
			)
			(layer "F.SilkS")
		)
		(fp_line
			(start 0 -0.902)
			(end 0.498 -0.902)
			(stroke
				(width 0.15)
				(type solid)
			)
			(layer "F.SilkS")
		)
		(fp_line
			(start 0 -0.902)
			(end -0.5 -0.902)
			(stroke
				(width 0.15)
				(type solid)
			)
			(layer "F.SilkS")
		)
		(fp_rect
			(start -2.25 -1.05)
			(end 2.25 1.05)
			(stroke
				(width 0.05)
				(type solid)
			)
			(fill no)
			(layer "F.CrtYd")
		)
		(fp_line
			(start 1.6 -0.802)
			(end 1.6 0.8)
			(stroke
				(width 0.15)
				(type solid)
			)
			(layer "F.Fab")
		)
		(fp_line
			(start -1.601 0.8)
			(end 1.6 0.8)
			(stroke
				(width 0.15)
				(type solid)
			)
			(layer "F.Fab")
		)
		(fp_line
			(start -1.601 -0.802)
			(end 1.6 -0.802)
			(stroke
				(width 0.15)
				(type solid)
			)
			(layer "F.Fab")
		)
		(fp_line
			(start -1.601 -0.802)
			(end -1.601 0.8)
			(stroke
				(width 0.15)
				(type solid)
			)
			(layer "F.Fab")
		)
		(pad "1" smd roundrect
			(at -1.5 0 180)
			(size 1.2 1.8)
			(layers "F.Cu" "F.Mask" "F.Paste")
			(roundrect_rratio 0.15)
			(net 58 "/Supply/1V7_local")
			(pintype "passive")
		)
		(pad "2" smd roundrect
			(at 1.499 0 180)
			(size 1.2 1.8)
			(layers "F.Cu" "F.Mask" "F.Paste")
			(roundrect_rratio 0.15)
			(net 64 "/Supply/1V7")
			(pintype "passive")
		)
	)
	(footprint "antmicro-footprints:SW_KMR211NGLFS_SMD"
		(layer "F.Cu")
		(at 202.95 137.6 -90)
		(property "Reference" "SW5"
			(at 1.1 2.05 270)
			(layer "F.SilkS")
			(effects
				(font
					(size 0.7 0.7)
					(thickness 0.15)
				)
				(justify left bottom)
			)
		)
		(property "Value" "SW_KMR211NGLFS_SMD"
			(at 0 2.8 270)
			(layer "F.Fab")
			(effects
				(font
					(size 0.7 0.7)
					(thickness 0.15)
				)
				(justify left bottom)
			)
		)
		(property "Datasheet" "http://www.farnell.com/datasheets/2631211.pdf"
			(at 0 0 270)
			(layer "F.Fab")
			(hide yes)
			(effects
				(font
					(size 1.27 1.27)
					(thickness 0.15)
				)
			)
		)
		(property "Author" "Antmicro"
			(at 65.35 340.55 0)
			(layer "F.Fab")
			(hide yes)
			(effects
				(font
					(size 1 1)
					(thickness 0.15)
				)
			)
		)
		(property "License" "Apache-2.0"
			(at 65.35 340.55 0)
			(layer "F.Fab")
			(hide yes)
			(effects
				(font
					(size 1 1)
					(thickness 0.15)
				)
			)
		)
		(property "MPN" "KMR211NGLFS"
			(at 65.35 340.55 0)
			(layer "F.Fab")
			(hide yes)
			(effects
				(font
					(size 1 1)
					(thickness 0.15)
				)
			)
		)
		(property "Manufacturer" "C&K"
			(at 65.35 340.55 0)
			(layer "F.Fab")
			(hide yes)
			(effects
				(font
					(size 1 1)
					(thickness 0.15)
				)
			)
		)
		(sheetname "/Supply/")
		(sheetfile "supply.kicad_sch")
		(attr smd)
		(fp_line
			(start -2.1 1.601)
			(end -2.1 1.48)
			(stroke
				(width 0.15)
				(type solid)
			)
			(layer "F.SilkS")
		)
		(fp_line
			(start 2.101 1.601)
			(end -2.1 1.601)
			(stroke
				(width 0.15)
				(type solid)
			)
			(layer "F.SilkS")
		)
		(fp_line
			(start 2.101 1.601)
			(end 2.101 1.48)
			(stroke
				(width 0.15)
				(type solid)
			)
			(layer "F.SilkS")
		)
		(fp_line
			(start 2.101 -1.58)
			(end 2.101 -1.459)
			(stroke
				(width 0.15)
				(type solid)
			)
			(layer "F.SilkS")
		)
		(fp_line
			(start -2.1 -1.6)
			(end -2.1 -1.499)
			(stroke
				(width 0.15)
				(type solid)
			)
			(layer "F.SilkS")
		)
		(fp_line
			(start 2.101 -1.6)
			(end -2.1 -1.6)
			(stroke
				(width 0.15)
				(type solid)
			)
			(layer "F.SilkS")
		)
		(fp_rect
			(start 2.751 1.75)
			(end -2.748 -1.749)
			(stroke
				(width 0.05)
				(type solid)
			)
			(fill no)
			(layer "F.CrtYd")
		)
		(fp_line
			(start -2.1 1.601)
			(end 2.101 1.601)
			(stroke
				(width 0.15)
				(type solid)
			)
			(layer "F.Fab")
		)
		(fp_line
			(start 2.101 1.601)
			(end 2.101 -1.6)
			(stroke
				(width 0.15)
				(type solid)
			)
			(layer "F.Fab")
		)
		(fp_line
			(start 0.25 0.802)
			(end -0.248 0.802)
			(stroke
				(width 0.15)
				(type solid)
			)
			(layer "F.Fab")
		)
		(fp_line
			(start -0.248 -0.8)
			(end 0.25 -0.8)
			(stroke
				(width 0.15)
				(type solid)
			)
			(layer "F.Fab")
		)
		(fp_line
			(start -2.1 -1.6)
			(end -2.1 1.601)
			(stroke
				(width 0.15)
				(type solid)
			)
			(layer "F.Fab")
		)
		(fp_line
			(start 2.101 -1.6)
			(end -2.1 -1.6)
			(stroke
				(width 0.15)
				(type solid)
			)
			(layer "F.Fab")
		)
		(fp_arc
			(start -0.248 0.802)
			(mid -1.050001 0.001)
			(end -0.248 -0.8)
			(stroke
				(width 0.15)
				(type solid)
			)
			(layer "F.Fab")
		)
		(fp_arc
			(start 0.25 -0.8)
			(mid 1.051001 0.001)
			(end 0.25 0.802)
			(stroke
				(width 0.15)
				(type solid)
			)
			(layer "F.Fab")
		)
		(pad "1" smd rect
			(at -2.048 -0.8 90)
			(size 0.9 1)
			(layers "F.Cu" "F.Mask" "F.Paste")
			(net 1 "GND")
			(pinfunction "1")
			(pintype "passive")
		)
		(pad "2" smd rect
			(at 2.05 -0.8 90)
			(size 0.9 1)
			(layers "F.Cu" "F.Mask" "F.Paste")
			(net 1 "GND")
			(pinfunction "2")
			(pintype "passive")
		)
		(pad "3" smd rect
			(at -2.048 0.802 90)
			(size 0.9 1)
			(layers "F.Cu" "F.Mask" "F.Paste")
			(net 252 "/Supply/~{PB_CTRL_IN}")
			(pinfunction "3")
			(pintype "passive")
		)
		(pad "4" smd rect
			(at 2.05 0.802 90)
			(size 0.9 1)
			(layers "F.Cu" "F.Mask" "F.Paste")
			(net 252 "/Supply/~{PB_CTRL_IN}")
			(pinfunction "4")
			(pintype "passive")
		)
	)
	(footprint "antmicro-footprints:R_1206_3216Metric"
		(layer "F.Cu")
		(at 199.5 173.975 180)
		(property "Reference" "R148"
			(at 5.05 0.125 180)
			(layer "F.SilkS")
			(effects
				(font
					(size 0.7 0.7)
					(thickness 0.15)
				)
				(justify left bottom)
			)
		)
		(property "Value" "R_0R01_1206"
			(at -2.422356 2.103591 180)
			(layer "F.Fab")
			(effects
				(font
					(size 0.7 0.7)
					(thickness 0.15)
				)
				(justify left bottom)
			)
		)
		(property "Datasheet" "https://www.yageo.com/upload/media/product/productsearch/datasheet/rchip/PYu-RL_Group_521_RoHS_L_2.pdf"
			(at 0 0 180)
			(layer "F.Fab")
			(hide yes)
			(effects
				(font
					(size 1.27 1.27)
					(thickness 0.15)
				)
			)
		)
		(property "Author" "Antmicro"
			(at 399 347.95 0)
			(layer "F.Fab")
			(hide yes)
			(effects
				(font
					(size 1 1)
					(thickness 0.15)
				)
			)
		)
		(property "License" "Apache-2.0"
			(at 399 347.95 0)
			(layer "F.Fab")
			(hide yes)
			(effects
				(font
					(size 1 1)
					(thickness 0.15)
				)
			)
		)
		(property "MPN" "RL1206FR-7W0R01L"
			(at 399 347.95 0)
			(layer "F.Fab")
			(hide yes)
			(effects
				(font
					(size 1 1)
					(thickness 0.15)
				)
			)
		)
		(property "Manufacturer" "YAGEO"
			(at 399 347.95 0)
			(layer "F.Fab")
			(hide yes)
			(effects
				(font
					(size 1 1)
					(thickness 0.15)
				)
			)
		)
		(property "Tolerance" "1%"
			(at 399 347.95 0)
			(layer "F.Fab")
			(hide yes)
			(effects
				(font
					(size 1 1)
					(thickness 0.15)
				)
			)
		)
		(property "Val" "0R01"
			(at 399 347.95 0)
			(layer "F.Fab")
			(hide yes)
			(effects
				(font
					(size 1 1)
					(thickness 0.15)
				)
			)
		)
		(sheetname "/Supply/")
		(sheetfile "supply.kicad_sch")
		(attr smd)
		(fp_line
			(start 0 0.9)
			(end 0.498 0.9)
			(stroke
				(width 0.15)
				(type solid)
			)
			(layer "F.SilkS")
		)
		(fp_line
			(start 0 0.9)
			(end -0.5 0.9)
			(stroke
				(width 0.15)
				(type solid)
			)
			(layer "F.SilkS")
		)
		(fp_line
			(start 0 -0.902)
			(end 0.498 -0.902)
			(stroke
				(width 0.15)
				(type solid)
			)
			(layer "F.SilkS")
		)
		(fp_line
			(start 0 -0.902)
			(end -0.5 -0.902)
			(stroke
				(width 0.15)
				(type solid)
			)
			(layer "F.SilkS")
		)
		(fp_rect
			(start -2.25 -1.05)
			(end 2.25 1.05)
			(stroke
				(width 0.05)
				(type solid)
			)
			(fill no)
			(layer "F.CrtYd")
		)
		(fp_line
			(start 1.6 -0.802)
			(end 1.6 0.8)
			(stroke
				(width 0.15)
				(type solid)
			)
			(layer "F.Fab")
		)
		(fp_line
			(start -1.601 0.8)
			(end 1.6 0.8)
			(stroke
				(width 0.15)
				(type solid)
			)
			(layer "F.Fab")
		)
		(fp_line
			(start -1.601 -0.802)
			(end 1.6 -0.802)
			(stroke
				(width 0.15)
				(type solid)
			)
			(layer "F.Fab")
		)
		(fp_line
			(start -1.601 -0.802)
			(end -1.601 0.8)
			(stroke
				(width 0.15)
				(type solid)
			)
			(layer "F.Fab")
		)
		(pad "1" smd roundrect
			(at -1.5 0 180)
			(size 1.2 1.8)
			(layers "F.Cu" "F.Mask" "F.Paste")
			(roundrect_rratio 0.15)
			(net 56 "/Supply/1V2_local")
			(pintype "passive")
		)
		(pad "2" smd roundrect
			(at 1.499 0 180)
			(size 1.2 1.8)
			(layers "F.Cu" "F.Mask" "F.Paste")
			(roundrect_rratio 0.15)
			(net 199 "+1V2")
			(pintype "passive")
		)
	)
)
